(kicad_pcb
	(version 20260206)
	(generator "pcbnew")
	(generator_version "10.0")
	(general
		(thickness 1.6)
		(legacy_teardrops no)
	)
	(paper "A4")
	(title_block
		(title "peb — Lightning_PEB_BRD.brd")
		(comment 1 "Lightning (Wiwynn / Facebook NVMe JBOF) / footprints 1717-1723 of 2563")
	)
	(layers
		(0 "F.Cu" signal "TOP")
		(4 "In1.Cu" signal "L2GND")
		(6 "In2.Cu" signal "L3")
		(8 "In3.Cu" signal "L4VCC")
		(10 "In4.Cu" signal "L5VCC")
		(12 "In5.Cu" signal "L6")
		(14 "In6.Cu" signal "L7GND")
		(2 "B.Cu" signal "BOTTOM")
		(9 "F.Adhes" user "F.Adhesive")
		(11 "B.Adhes" user "B.Adhesive")
		(13 "F.Paste" user "Package Geometry/Pastemask Top")
		(15 "B.Paste" user "Package Geometry/Pastemask Bottom")
		(5 "F.SilkS" user "Ref Des/Silkscreen Top")
		(7 "B.SilkS" user "Ref Des/Silkscreen Bottom")
		(1 "F.Mask" user "Board Geometry/Soldermask Top")
		(3 "B.Mask" user "Board Geometry/Soldermask Bottom")
		(17 "Dwgs.User" user "User.Drawings")
		(19 "Cmts.User" user "User.Comments")
		(21 "Eco1.User" user "User.Eco1")
		(23 "Eco2.User" user "User.Eco2")
		(25 "Edge.Cuts" user "Board Geometry/Outline")
		(27 "Margin" user)
		(31 "F.CrtYd" user "Package Geometry/Place Bound Top")
		(29 "B.CrtYd" user "Package Geometry/Place Bound Bottom")
		(35 "F.Fab" user "Ref Des/Assembly Top")
		(33 "B.Fab" user "Ref Des/Assembly Bottom")
	)
	(footprint ""
		(layer "B.Cu")
		(at 227.6856 -35.995356 -90)
		(property "Reference" "C568"
			(at 0 0 90)
			(layer "B.SilkS")
			(hide yes)
			(effects
				(font
					(size 1.27 1.27)
				)
				(justify mirror)
			)
		)
		(property "Value" "SCD1U16V1KX-1-GP"
			(at 2.8321 -1.7399 270)
			(unlocked yes)
			(layer "B.Fab")
			(hide yes)
			(effects
				(font
					(size 1.016 1.016)
					(thickness 0.1524)
				)
				(justify mirror)
			)
		)
		(property "Device Type" "C0201H13"
			(at 2.8321 -3.2639 270)
			(unlocked yes)
			(layer "B.Fab")
			(hide yes)
			(effects
				(font
					(size 1.016 1.016)
					(thickness 0.1524)
				)
				(justify mirror)
			)
		)
		(duplicate_pad_numbers_are_jumpers no)
		(fp_rect
			(start 0.2794 0.6477)
			(end -0.2794 -0.6477)
			(stroke
				(width 0)
				(type default)
			)
			(fill no)
			(layer "B.CrtYd")
		)
		(fp_rect
			(start 0.2794 0.6477)
			(end -0.2794 -0.6477)
			(stroke
				(width 0)
				(type default)
			)
			(fill no)
			(layer "B.Fab")
		)
		(pad "1" smd custom
			(at 0 -0.2794 90)
			(size 0.0762 0.0762)
			(layers "B.Cu" "B.Mask" "B.Paste")
			(net "DUT_AVD_PCIE")
			(options
				(clearance outline)
				(anchor circle)
			)
			(primitives
				(gr_poly
					(pts
						(arc
							(start 0.1524 0.127)
							(mid 0.137521 0.162921)
							(end 0.1016 0.1778)
						)
						(arc
							(start -0.1016 0.1778)
							(mid -0.137521 0.162921)
							(end -0.1524 0.127)
						)
						(arc
							(start -0.1524 -0.127)
							(mid -0.137521 -0.162921)
							(end -0.1016 -0.1778)
						)
						(arc
							(start 0.1016 -0.1778)
							(mid 0.137521 -0.162921)
							(end 0.1524 -0.127)
						)
					)
					(width 0)
					(fill yes)
				)
			)
		)
		(pad "2" smd custom
			(at 0 0.2794 90)
			(size 0.0762 0.0762)
			(layers "B.Cu" "B.Mask" "B.Paste")
			(net "GND")
			(options
				(clearance outline)
				(anchor circle)
			)
			(primitives
				(gr_poly
					(pts
						(arc
							(start 0.1524 0.127)
							(mid 0.137521 0.162921)
							(end 0.1016 0.1778)
						)
						(arc
							(start -0.1016 0.1778)
							(mid -0.137521 0.162921)
							(end -0.1524 0.127)
						)
						(arc
							(start -0.1524 -0.127)
							(mid -0.137521 -0.162921)
							(end -0.1016 -0.1778)
						)
						(arc
							(start 0.1016 -0.1778)
							(mid 0.137521 -0.162921)
							(end 0.1524 -0.127)
						)
					)
					(width 0)
					(fill yes)
				)
			)
		)
	)
	(footprint ""
		(layer "B.Cu")
		(at 332.0796 -175.7426)
		(property "Reference" "C3214"
			(at 0 0 0)
			(layer "B.SilkS")
			(hide yes)
			(effects
				(font
					(size 1.27 1.27)
				)
				(justify mirror)
			)
		)
		(property "Value" "SCD1U25V2KX-2-GP"
			(at -1.1811 -2.7051 0)
			(unlocked yes)
			(layer "B.Fab")
			(hide yes)
			(effects
				(font
					(size 1.016 1.016)
					(thickness 0.1524)
				)
				(justify mirror)
			)
		)
		(property "Device Type" "C402H22"
			(at -1.1811 -4.2291 0)
			(unlocked yes)
			(layer "B.Fab")
			(hide yes)
			(effects
				(font
					(size 1.016 1.016)
					(thickness 0.1524)
				)
				(justify mirror)
			)
		)
		(duplicate_pad_numbers_are_jumpers no)
		(fp_rect
			(start 0.4318 0.9525)
			(end -0.4318 -0.9525)
			(stroke
				(width 0)
				(type default)
			)
			(fill no)
			(layer "B.CrtYd")
		)
		(fp_rect
			(start 0.4318 0.9525)
			(end -0.4318 -0.9525)
			(stroke
				(width 0)
				(type default)
			)
			(fill no)
			(layer "B.Fab")
		)
		(pad "1" smd custom
			(at 0 -0.4445 180)
			(size 0.1524 0.1524)
			(layers "B.Cu" "B.Mask" "B.Paste")
			(net "P3V3_STBY")
			(options
				(clearance outline)
				(anchor circle)
			)
			(primitives
				(gr_poly
					(pts
						(arc
							(start 0.3048 0.2032)
							(mid 0.275042 0.275042)
							(end 0.2032 0.3048)
						)
						(arc
							(start -0.2032 0.3048)
							(mid -0.275042 0.275042)
							(end -0.3048 0.2032)
						)
						(arc
							(start -0.3048 -0.2032)
							(mid -0.275042 -0.275042)
							(end -0.2032 -0.3048)
						)
						(arc
							(start 0.2032 -0.3048)
							(mid 0.275042 -0.275042)
							(end 0.3048 -0.2032)
						)
					)
					(width 0)
					(fill yes)
				)
			)
		)
		(pad "2" smd custom
			(at 0 0.4445 180)
			(size 0.1524 0.1524)
			(layers "B.Cu" "B.Mask" "B.Paste")
			(net "GND")
			(options
				(clearance outline)
				(anchor circle)
			)
			(primitives
				(gr_poly
					(pts
						(arc
							(start 0.3048 0.2032)
							(mid 0.275042 0.275042)
							(end 0.2032 0.3048)
						)
						(arc
							(start -0.2032 0.3048)
							(mid -0.275042 0.275042)
							(end -0.3048 0.2032)
						)
						(arc
							(start -0.3048 -0.2032)
							(mid -0.275042 -0.275042)
							(end -0.2032 -0.3048)
						)
						(arc
							(start 0.2032 -0.3048)
							(mid 0.275042 -0.275042)
							(end 0.3048 -0.2032)
						)
					)
					(width 0)
					(fill yes)
				)
			)
		)
	)
	(footprint ""
		(layer "B.Cu")
		(at 331.724 -181.61)
		(property "Reference" "C8093"
			(at 0 0 0)
			(layer "B.SilkS")
			(hide yes)
			(effects
				(font
					(size 1.27 1.27)
				)
				(justify mirror)
			)
		)
		(property "Value" "SCD047U25V2KX-GP"
			(at -1.1811 -2.7051 0)
			(unlocked yes)
			(layer "B.Fab")
			(hide yes)
			(effects
				(font
					(size 1.016 1.016)
					(thickness 0.1524)
				)
				(justify mirror)
			)
		)
		(property "Device Type" "C402H22"
			(at -1.1811 -4.2291 0)
			(unlocked yes)
			(layer "B.Fab")
			(hide yes)
			(effects
				(font
					(size 1.016 1.016)
					(thickness 0.1524)
				)
				(justify mirror)
			)
		)
		(duplicate_pad_numbers_are_jumpers no)
		(fp_rect
			(start 0.4318 0.9525)
			(end -0.4318 -0.9525)
			(stroke
				(width 0)
				(type default)
			)
			(fill no)
			(layer "B.CrtYd")
		)
		(fp_rect
			(start 0.4318 0.9525)
			(end -0.4318 -0.9525)
			(stroke
				(width 0)
				(type default)
			)
			(fill no)
			(layer "B.Fab")
		)
		(pad "1" smd custom
			(at 0 -0.4445 180)
			(size 0.1524 0.1524)
			(layers "B.Cu" "B.Mask" "B.Paste")
			(net "P3V3_STBY")
			(options
				(clearance outline)
				(anchor circle)
			)
			(primitives
				(gr_poly
					(pts
						(arc
							(start 0.3048 0.2032)
							(mid 0.275042 0.275042)
							(end 0.2032 0.3048)
						)
						(arc
							(start -0.2032 0.3048)
							(mid -0.275042 0.275042)
							(end -0.3048 0.2032)
						)
						(arc
							(start -0.3048 -0.2032)
							(mid -0.275042 -0.275042)
							(end -0.2032 -0.3048)
						)
						(arc
							(start 0.2032 -0.3048)
							(mid 0.275042 -0.275042)
							(end 0.3048 -0.2032)
						)
					)
					(width 0)
					(fill yes)
				)
			)
		)
		(pad "2" smd custom
			(at 0 0.4445 180)
			(size 0.1524 0.1524)
			(layers "B.Cu" "B.Mask" "B.Paste")
			(net "GND")
			(options
				(clearance outline)
				(anchor circle)
			)
			(primitives
				(gr_poly
					(pts
						(arc
							(start 0.3048 0.2032)
							(mid 0.275042 0.275042)
							(end 0.2032 0.3048)
						)
						(arc
							(start -0.2032 0.3048)
							(mid -0.275042 0.275042)
							(end -0.3048 0.2032)
						)
						(arc
							(start -0.3048 -0.2032)
							(mid -0.275042 -0.275042)
							(end -0.2032 -0.3048)
						)
						(arc
							(start 0.2032 -0.3048)
							(mid 0.275042 -0.275042)
							(end 0.3048 -0.2032)
						)
					)
					(width 0)
					(fill yes)
				)
			)
		)
	)
	(footprint ""
		(layer "B.Cu")
		(at 133.858 -196.3928)
		(property "Reference" "R4130"
			(at 0 0 0)
			(layer "B.SilkS")
			(hide yes)
			(effects
				(font
					(size 1.27 1.27)
				)
				(justify mirror)
			)
		)
		(property "Value" "4K7R2F-GP"
			(at -0.064008 -3.993896 0)
			(unlocked yes)
			(layer "B.Fab")
			(hide yes)
			(effects
				(font
					(size 1.016 1.016)
					(thickness 0.1524)
				)
				(justify mirror)
			)
		)
		(property "Device Type" "R402H16"
			(at -0.064008 -5.517896 0)
			(unlocked yes)
			(layer "B.Fab")
			(hide yes)
			(effects
				(font
					(size 1.016 1.016)
					(thickness 0.1524)
				)
				(justify mirror)
			)
		)
		(duplicate_pad_numbers_are_jumpers no)
		(fp_line
			(start -0.508 -0.9398)
			(end 0.508 -0.9398)
			(stroke
				(width 0.1524)
				(type default)
			)
			(layer "B.SilkS")
		)
		(fp_line
			(start 0.508 -0.9398)
			(end 0.508 0.9398)
			(stroke
				(width 0.1524)
				(type default)
			)
			(layer "B.SilkS")
		)
		(fp_rect
			(start 0.508 0.9398)
			(end -0.508 -0.9398)
			(stroke
				(width 0)
				(type default)
			)
			(fill no)
			(layer "B.CrtYd")
		)
		(fp_rect
			(start 0.508 0.9398)
			(end -0.508 -0.9398)
			(stroke
				(width 0)
				(type default)
			)
			(fill no)
			(layer "B.Fab")
		)
		(pad "1" smd custom
			(at 0 -0.4445 180)
			(size 0.1397 0.1397)
			(layers "B.Cu" "B.Mask" "B.Paste")
			(net "SSD_PERST#2")
			(options
				(clearance outline)
				(anchor circle)
			)
			(primitives
				(gr_poly
					(pts
						(arc
							(start -0.1778 0.2794)
							(mid -0.249642 0.249642)
							(end -0.2794 0.1778)
						)
						(arc
							(start -0.2794 -0.1778)
							(mid -0.249642 -0.249642)
							(end -0.1778 -0.2794)
						)
						(arc
							(start 0.1778 -0.2794)
							(mid 0.249642 -0.249642)
							(end 0.2794 -0.1778)
						)
						(arc
							(start 0.2794 0.1778)
							(mid 0.249642 0.249642)
							(end 0.1778 0.2794)
						)
					)
					(width 0)
					(fill yes)
				)
			)
		)
		(pad "2" smd custom
			(at 0 0.4445 180)
			(size 0.1397 0.1397)
			(layers "B.Cu" "B.Mask" "B.Paste")
			(net "P3V3_STBY")
			(options
				(clearance outline)
				(anchor circle)
			)
			(primitives
				(gr_poly
					(pts
						(arc
							(start -0.1778 0.2794)
							(mid -0.249642 0.249642)
							(end -0.2794 0.1778)
						)
						(arc
							(start -0.2794 -0.1778)
							(mid -0.249642 -0.249642)
							(end -0.1778 -0.2794)
						)
						(arc
							(start 0.1778 -0.2794)
							(mid 0.249642 -0.249642)
							(end 0.2794 -0.1778)
						)
						(arc
							(start 0.2794 0.1778)
							(mid 0.249642 0.249642)
							(end 0.1778 0.2794)
						)
					)
					(width 0)
					(fill yes)
				)
			)
		)
	)
	(footprint ""
		(layer "B.Cu")
		(at 253.5936 -38.002972 90)
		(property "Reference" "C592"
			(at 0 0 90)
			(layer "B.SilkS")
			(hide yes)
			(effects
				(font
					(size 1.27 1.27)
				)
				(justify mirror)
			)
		)
		(property "Value" "SCD1U16V1KX-1-GP"
			(at 2.8321 -1.7399 90)
			(unlocked yes)
			(layer "B.Fab")
			(hide yes)
			(effects
				(font
					(size 1.016 1.016)
					(thickness 0.1524)
				)
				(justify mirror)
			)
		)
		(property "Device Type" "C0201H13"
			(at 2.8321 -3.2639 90)
			(unlocked yes)
			(layer "B.Fab")
			(hide yes)
			(effects
				(font
					(size 1.016 1.016)
					(thickness 0.1524)
				)
				(justify mirror)
			)
		)
		(duplicate_pad_numbers_are_jumpers no)
		(fp_rect
			(start 0.2794 0.6477)
			(end -0.2794 -0.6477)
			(stroke
				(width 0)
				(type default)
			)
			(fill no)
			(layer "B.CrtYd")
		)
		(fp_rect
			(start 0.2794 0.6477)
			(end -0.2794 -0.6477)
			(stroke
				(width 0)
				(type default)
			)
			(fill no)
			(layer "B.Fab")
		)
		(pad "1" smd custom
			(at 0 -0.2794 270)
			(size 0.0762 0.0762)
			(layers "B.Cu" "B.Mask" "B.Paste")
			(net "DUT_AVD_PCIE")
			(options
				(clearance outline)
				(anchor circle)
			)
			(primitives
				(gr_poly
					(pts
						(arc
							(start 0.1524 0.127)
							(mid 0.137521 0.162921)
							(end 0.1016 0.1778)
						)
						(arc
							(start -0.1016 0.1778)
							(mid -0.137521 0.162921)
							(end -0.1524 0.127)
						)
						(arc
							(start -0.1524 -0.127)
							(mid -0.137521 -0.162921)
							(end -0.1016 -0.1778)
						)
						(arc
							(start 0.1016 -0.1778)
							(mid 0.137521 -0.162921)
							(end 0.1524 -0.127)
						)
					)
					(width 0)
					(fill yes)
				)
			)
		)
		(pad "2" smd custom
			(at 0 0.2794 270)
			(size 0.0762 0.0762)
			(layers "B.Cu" "B.Mask" "B.Paste")
			(net "GND")
			(options
				(clearance outline)
				(anchor circle)
			)
			(primitives
				(gr_poly
					(pts
						(arc
							(start 0.1524 0.127)
							(mid 0.137521 0.162921)
							(end 0.1016 0.1778)
						)
						(arc
							(start -0.1016 0.1778)
							(mid -0.137521 0.162921)
							(end -0.1524 0.127)
						)
						(arc
							(start -0.1524 -0.127)
							(mid -0.137521 -0.162921)
							(end -0.1016 -0.1778)
						)
						(arc
							(start 0.1016 -0.1778)
							(mid 0.137521 -0.162921)
							(end 0.1524 -0.127)
						)
					)
					(width 0)
					(fill yes)
				)
			)
		)
	)
	(footprint ""
		(layer "B.Cu")
		(at 126.976124 -196.443092)
		(property "Reference" "R4120"
			(at 0 0 0)
			(layer "B.SilkS")
			(hide yes)
			(effects
				(font
					(size 1.27 1.27)
				)
				(justify mirror)
			)
		)
		(property "Value" "4K7R2F-GP"
			(at -0.064008 -3.993896 0)
			(unlocked yes)
			(layer "B.Fab")
			(hide yes)
			(effects
				(font
					(size 1.016 1.016)
					(thickness 0.1524)
				)
				(justify mirror)
			)
		)
		(property "Device Type" "R402H16"
			(at -0.064008 -5.517896 0)
			(unlocked yes)
			(layer "B.Fab")
			(hide yes)
			(effects
				(font
					(size 1.016 1.016)
					(thickness 0.1524)
				)
				(justify mirror)
			)
		)
		(duplicate_pad_numbers_are_jumpers no)
		(fp_line
			(start -0.508 -0.9398)
			(end 0.508 -0.9398)
			(stroke
				(width 0.1524)
				(type default)
			)
			(layer "B.SilkS")
		)
		(fp_line
			(start 0.508 -0.9398)
			(end 0.508 0.9398)
			(stroke
				(width 0.1524)
				(type default)
			)
			(layer "B.SilkS")
		)
		(fp_rect
			(start 0.508 0.9398)
			(end -0.508 -0.9398)
			(stroke
				(width 0)
				(type default)
			)
			(fill no)
			(layer "B.CrtYd")
		)
		(fp_rect
			(start 0.508 0.9398)
			(end -0.508 -0.9398)
			(stroke
				(width 0)
				(type default)
			)
			(fill no)
			(layer "B.Fab")
		)
		(pad "1" smd custom
			(at 0 -0.4445 180)
			(size 0.1397 0.1397)
			(layers "B.Cu" "B.Mask" "B.Paste")
			(net "SSD_ATNLED#1")
			(options
				(clearance outline)
				(anchor circle)
			)
			(primitives
				(gr_poly
					(pts
						(arc
							(start -0.1778 0.2794)
							(mid -0.249642 0.249642)
							(end -0.2794 0.1778)
						)
						(arc
							(start -0.2794 -0.1778)
							(mid -0.249642 -0.249642)
							(end -0.1778 -0.2794)
						)
						(arc
							(start 0.1778 -0.2794)
							(mid 0.249642 -0.249642)
							(end 0.2794 -0.1778)
						)
						(arc
							(start 0.2794 0.1778)
							(mid 0.249642 0.249642)
							(end 0.1778 0.2794)
						)
					)
					(width 0)
					(fill yes)
				)
			)
		)
		(pad "2" smd custom
			(at 0 0.4445 180)
			(size 0.1397 0.1397)
			(layers "B.Cu" "B.Mask" "B.Paste")
			(net "P3V3_STBY")
			(options
				(clearance outline)
				(anchor circle)
			)
			(primitives
				(gr_poly
					(pts
						(arc
							(start -0.1778 0.2794)
							(mid -0.249642 0.249642)
							(end -0.2794 0.1778)
						)
						(arc
							(start -0.2794 -0.1778)
							(mid -0.249642 -0.249642)
							(end -0.1778 -0.2794)
						)
						(arc
							(start 0.1778 -0.2794)
							(mid 0.249642 -0.249642)
							(end 0.2794 -0.1778)
						)
						(arc
							(start 0.2794 0.1778)
							(mid 0.249642 0.249642)
							(end 0.1778 0.2794)
						)
					)
					(width 0)
					(fill yes)
				)
			)
		)
	)
	(footprint ""
		(layer "B.Cu")
		(at 340.7156 -175.7426)
		(property "Reference" "C3204"
			(at 0 0 0)
			(layer "B.SilkS")
			(hide yes)
			(effects
				(font
					(size 1.27 1.27)
				)
				(justify mirror)
			)
		)
		(property "Value" "SCD1U25V2KX-2-GP"
			(at -1.1811 -2.7051 0)
			(unlocked yes)
			(layer "B.Fab")
			(hide yes)
			(effects
				(font
					(size 1.016 1.016)
					(thickness 0.1524)
				)
				(justify mirror)
			)
		)
		(property "Device Type" "C402H22"
			(at -1.1811 -4.2291 0)
			(unlocked yes)
			(layer "B.Fab")
			(hide yes)
			(effects
				(font
					(size 1.016 1.016)
					(thickness 0.1524)
				)
				(justify mirror)
			)
		)
		(duplicate_pad_numbers_are_jumpers no)
		(fp_rect
			(start 0.4318 0.9525)
			(end -0.4318 -0.9525)
			(stroke
				(width 0)
				(type default)
			)
			(fill no)
			(layer "B.CrtYd")
		)
		(fp_rect
			(start 0.4318 0.9525)
			(end -0.4318 -0.9525)
			(stroke
				(width 0)
				(type default)
			)
			(fill no)
			(layer "B.Fab")
		)
		(pad "1" smd custom
			(at 0 -0.4445 180)
			(size 0.1524 0.1524)
			(layers "B.Cu" "B.Mask" "B.Paste")
			(net "P3V3_STBY")
			(options
				(clearance outline)
				(anchor circle)
			)
			(primitives
				(gr_poly
					(pts
						(arc
							(start 0.3048 0.2032)
							(mid 0.275042 0.275042)
							(end 0.2032 0.3048)
						)
						(arc
							(start -0.2032 0.3048)
							(mid -0.275042 0.275042)
							(end -0.3048 0.2032)
						)
						(arc
							(start -0.3048 -0.2032)
							(mid -0.275042 -0.275042)
							(end -0.2032 -0.3048)
						)
						(arc
							(start 0.2032 -0.3048)
							(mid 0.275042 -0.275042)
							(end 0.3048 -0.2032)
						)
					)
					(width 0)
					(fill yes)
				)
			)
		)
		(pad "2" smd custom
			(at 0 0.4445 180)
			(size 0.1524 0.1524)
			(layers "B.Cu" "B.Mask" "B.Paste")
			(net "GND")
			(options
				(clearance outline)
				(anchor circle)
			)
			(primitives
				(gr_poly
					(pts
						(arc
							(start 0.3048 0.2032)
							(mid 0.275042 0.275042)
							(end 0.2032 0.3048)
						)
						(arc
							(start -0.2032 0.3048)
							(mid -0.275042 0.275042)
							(end -0.3048 0.2032)
						)
						(arc
							(start -0.3048 -0.2032)
							(mid -0.275042 -0.275042)
							(end -0.2032 -0.3048)
						)
						(arc
							(start 0.2032 -0.3048)
							(mid 0.275042 -0.275042)
							(end 0.3048 -0.2032)
						)
					)
					(width 0)
					(fill yes)
				)
			)
		)
	)
)
